(kicad_pcb
	(version 20241229)
	(generator "pcbnew")
	(generator_version "9.0")
	(general
		(thickness 1.6642)
		(legacy_teardrops no)
	)
	(paper "A3")
	(title_block
		(title "PolarFire SoM")
		(date "2025-07-22")
		(rev "1.1.4")
		(company "Antmicro Ltd")
		(comment 1 "www.antmicro.com")
		(comment 9 "footprints 355-358 of 470")
	)
	(layers
		(0 "F.Cu" mixed)
		(4 "In1.Cu" power)
		(6 "In2.Cu" signal)
		(8 "In3.Cu" power)
		(10 "In4.Cu" signal)
		(12 "In5.Cu" power)
		(14 "In6.Cu" power)
		(16 "In7.Cu" signal)
		(18 "In8.Cu" power)
		(20 "In9.Cu" signal)
		(22 "In10.Cu" power)
		(24 "In11.Cu" signal)
		(26 "In12.Cu" signal)
		(2 "B.Cu" mixed)
		(9 "F.Adhes" user "F.Adhesive")
		(11 "B.Adhes" user "B.Adhesive")
		(13 "F.Paste" user)
		(15 "B.Paste" user)
		(5 "F.SilkS" user "F.Silkscreen")
		(7 "B.SilkS" user "B.Silkscreen")
		(1 "F.Mask" user)
		(3 "B.Mask" user)
		(17 "Dwgs.User" user "User.Drawings")
		(19 "Cmts.User" user "User.Comments")
		(21 "Eco1.User" user "User.Eco1")
		(23 "Eco2.User" user "User.Eco2")
		(25 "Edge.Cuts" user)
		(27 "Margin" user)
		(31 "F.CrtYd" user "F.Courtyard")
		(29 "B.CrtYd" user "B.Courtyard")
		(35 "F.Fab" user)
		(33 "B.Fab" user)
	)
	(footprint "antmicro-footprints:C_0402_1005Metric"
		(layer "B.Cu")
		(at 222.2168 117.3457 180)
		(descr "Capacitor SMD 0402")
		(tags "capacitor SMD 0402")
		(property "Reference" "C239"
			(at -1.6132 0.3957 0)
			(layer "B.SilkS")
			(effects
				(font
					(size 0.7 0.7)
					(thickness 0.15)
				)
				(justify left bottom mirror)
			)
		)
		(property "Value" "C_100n_0402"
			(at -1.022927 -2.155213 0)
			(layer "B.Fab")
			(hide yes)
			(effects
				(font
					(size 0.7 0.7)
					(thickness 0.15)
				)
				(justify left bottom mirror)
			)
		)
		(property "Datasheet" "https://www.murata.com/products/productdetail?partno=GRM155R61H104KE14%23"
			(at 0 0 180)
			(layer "F.Fab")
			(hide yes)
			(effects
				(font
					(size 1.27 1.27)
					(thickness 0.15)
				)
			)
		)
		(property "Description" "SMD Multilayer Ceramic Capacitor, 0.1 µF, 50 V, 0402 [1005 Metric], ± 10%, X5R, GRM Series"
			(at 0 0 180)
			(layer "F.Fab")
			(hide yes)
			(effects
				(font
					(size 1.27 1.27)
					(thickness 0.15)
				)
			)
		)
		(property "Author" "Antmicro"
			(at 444.4336 234.6914 0)
			(layer "B.Fab")
			(hide yes)
			(effects
				(font
					(size 1 1)
					(thickness 0.15)
				)
				(justify mirror)
			)
		)
		(property "Dielectric" "X5R"
			(at 444.4336 234.6914 0)
			(layer "B.Fab")
			(hide yes)
			(effects
				(font
					(size 1 1)
					(thickness 0.15)
				)
				(justify mirror)
			)
		)
		(property "License" "Apache-2.0"
			(at 444.4336 234.6914 0)
			(layer "B.Fab")
			(hide yes)
			(effects
				(font
					(size 1 1)
					(thickness 0.15)
				)
				(justify mirror)
			)
		)
		(property "MPN" "GRM155R61H104KE14D"
			(at 444.4336 234.6914 0)
			(layer "B.Fab")
			(hide yes)
			(effects
				(font
					(size 1 1)
					(thickness 0.15)
				)
				(justify mirror)
			)
		)
		(property "Manufacturer" "Murata"
			(at 444.4336 234.6914 0)
			(layer "B.Fab")
			(hide yes)
			(effects
				(font
					(size 1 1)
					(thickness 0.15)
				)
				(justify mirror)
			)
		)
		(property "Public" ""
			(at 444.4336 234.6914 0)
			(layer "B.Fab")
			(hide yes)
			(effects
				(font
					(size 1 1)
					(thickness 0.15)
				)
				(justify mirror)
			)
		)
		(property "Val" "100n"
			(at 444.4336 234.6914 0)
			(layer "B.Fab")
			(hide yes)
			(effects
				(font
					(size 1 1)
					(thickness 0.15)
				)
				(justify mirror)
			)
		)
		(property "Voltage" "50V"
			(at 444.4336 234.6914 0)
			(layer "B.Fab")
			(hide yes)
			(effects
				(font
					(size 1 1)
					(thickness 0.15)
				)
				(justify mirror)
			)
		)
		(sheetname "/Ethernet/")
		(sheetfile "ethernet.kicad_sch")
		(attr smd)
		(fp_rect
			(start -0.925 0.47)
			(end 0.925 -0.47)
			(stroke
				(width 0.05)
				(type default)
			)
			(fill no)
			(layer "B.CrtYd")
		)
		(fp_line
			(start 0.504 0.25)
			(end 0.504 -0.248)
			(stroke
				(width 0.15)
				(type solid)
			)
			(layer "B.Fab")
		)
		(fp_line
			(start 0.504 -0.248)
			(end -0.494 -0.248)
			(stroke
				(width 0.15)
				(type solid)
			)
			(layer "B.Fab")
		)
		(fp_line
			(start -0.494 0.25)
			(end 0.504 0.25)
			(stroke
				(width 0.15)
				(type solid)
			)
			(layer "B.Fab")
		)
		(fp_line
			(start -0.494 -0.248)
			(end -0.494 0.25)
			(stroke
				(width 0.15)
				(type solid)
			)
			(layer "B.Fab")
		)
		(fp_text user "${REFERENCE}"
			(at -0.939 -4.599 0)
			(layer "B.Fab")
			(effects
				(font
					(size 0.7 0.7)
					(thickness 0.15)
				)
				(justify left bottom mirror)
			)
		)
		(fp_text user "Author: Antmicro"
			(at -0.939 -3.399 0)
			(layer "B.Fab")
			(effects
				(font
					(size 0.7 0.7)
					(thickness 0.15)
				)
				(justify left bottom mirror)
			)
		)
		(fp_text user "License: Apache-2.0"
			(at -0.939 -5.799 0)
			(layer "B.Fab")
			(effects
				(font
					(size 0.7 0.7)
					(thickness 0.15)
				)
				(justify left bottom mirror)
			)
		)
		(pad "1" smd roundrect
			(at -0.48 0 180)
			(size 0.59 0.64)
			(layers "B.Cu" "B.Mask" "B.Paste")
			(roundrect_rratio 0.25)
			(net 417 "GND")
			(pintype "passive")
		)
		(pad "2" smd roundrect
			(at 0.48 0 180)
			(size 0.59 0.64)
			(layers "B.Cu" "B.Mask" "B.Paste")
			(roundrect_rratio 0.25)
			(net 50 "+3V3")
			(pintype "passive")
		)
	)
	(footprint "antmicro-footprints:C_0402_1005Metric"
		(layer "B.Cu")
		(at 192.45 146.75 -90)
		(descr "Capacitor SMD 0402")
		(tags "capacitor SMD 0402")
		(property "Reference" "C189"
			(at 0.8 -0.7 90)
			(layer "B.SilkS")
			(effects
				(font
					(size 0.7 0.7)
					(thickness 0.15)
				)
				(justify left bottom mirror)
			)
		)
		(property "Value" "C_10u_10V_0402"
			(at -1.022927 -2.155213 90)
			(layer "B.Fab")
			(hide yes)
			(effects
				(font
					(size 0.7 0.7)
					(thickness 0.15)
				)
				(justify left bottom mirror)
			)
		)
		(property "Datasheet" "https://www.murata.com/products/productdetail?partno=GRM155R61A106ME11%23"
			(at 0 0 270)
			(layer "F.Fab")
			(hide yes)
			(effects
				(font
					(size 1.27 1.27)
					(thickness 0.15)
				)
			)
		)
		(property "Description" "Multilayer Ceramic Capacitors MLCC - SMD/SMT 10 uF 10 VDC 20% 0402 X5R"
			(at 0 0 270)
			(layer "F.Fab")
			(hide yes)
			(effects
				(font
					(size 1.27 1.27)
					(thickness 0.15)
				)
			)
		)
		(property "Author" "Antmicro"
			(at 45.7 339.2 0)
			(layer "B.Fab")
			(hide yes)
			(effects
				(font
					(size 1 1)
					(thickness 0.15)
				)
				(justify mirror)
			)
		)
		(property "Dielectric" "X5R"
			(at 45.7 339.2 0)
			(layer "B.Fab")
			(hide yes)
			(effects
				(font
					(size 1 1)
					(thickness 0.15)
				)
				(justify mirror)
			)
		)
		(property "License" "Apache-2.0"
			(at 45.7 339.2 0)
			(layer "B.Fab")
			(hide yes)
			(effects
				(font
					(size 1 1)
					(thickness 0.15)
				)
				(justify mirror)
			)
		)
		(property "MPN" "GRM155R61A106ME11D"
			(at 45.7 339.2 0)
			(layer "B.Fab")
			(hide yes)
			(effects
				(font
					(size 1 1)
					(thickness 0.15)
				)
				(justify mirror)
			)
		)
		(property "Manufacturer" "Murata"
			(at 45.7 339.2 0)
			(layer "B.Fab")
			(hide yes)
			(effects
				(font
					(size 1 1)
					(thickness 0.15)
				)
				(justify mirror)
			)
		)
		(property "Public" ""
			(at 45.7 339.2 0)
			(layer "B.Fab")
			(hide yes)
			(effects
				(font
					(size 1 1)
					(thickness 0.15)
				)
				(justify mirror)
			)
		)
		(property "Val" "10u"
			(at 45.7 339.2 0)
			(layer "B.Fab")
			(hide yes)
			(effects
				(font
					(size 1 1)
					(thickness 0.15)
				)
				(justify mirror)
			)
		)
		(property "Voltage" "10V"
			(at 45.7 339.2 0)
			(layer "B.Fab")
			(hide yes)
			(effects
				(font
					(size 1 1)
					(thickness 0.15)
				)
				(justify mirror)
			)
		)
		(sheetname "/HDMI/")
		(sheetfile "hdmi.kicad_sch")
		(attr smd)
		(fp_rect
			(start -0.925 0.47)
			(end 0.925 -0.47)
			(stroke
				(width 0.05)
				(type default)
			)
			(fill no)
			(layer "B.CrtYd")
		)
		(fp_line
			(start -0.494 0.25)
			(end 0.504 0.25)
			(stroke
				(width 0.15)
				(type solid)
			)
			(layer "B.Fab")
		)
		(fp_line
			(start 0.504 0.25)
			(end 0.504 -0.248)
			(stroke
				(width 0.15)
				(type solid)
			)
			(layer "B.Fab")
		)
		(fp_line
			(start -0.494 -0.248)
			(end -0.494 0.25)
			(stroke
				(width 0.15)
				(type solid)
			)
			(layer "B.Fab")
		)
		(fp_line
			(start 0.504 -0.248)
			(end -0.494 -0.248)
			(stroke
				(width 0.15)
				(type solid)
			)
			(layer "B.Fab")
		)
		(fp_text user "License: Apache-2.0"
			(at -0.939 -5.799 90)
			(layer "B.Fab")
			(effects
				(font
					(size 0.7 0.7)
					(thickness 0.15)
				)
				(justify left bottom mirror)
			)
		)
		(fp_text user "${REFERENCE}"
			(at -0.939 -4.599 90)
			(layer "B.Fab")
			(effects
				(font
					(size 0.7 0.7)
					(thickness 0.15)
				)
				(justify left bottom mirror)
			)
		)
		(fp_text user "Author: Antmicro"
			(at -0.939 -3.399 90)
			(layer "B.Fab")
			(effects
				(font
					(size 0.7 0.7)
					(thickness 0.15)
				)
				(justify left bottom mirror)
			)
		)
		(pad "1" smd roundrect
			(at -0.48 0 270)
			(size 0.59 0.64)
			(layers "B.Cu" "B.Mask" "B.Paste")
			(roundrect_rratio 0.25)
			(net 417 "GND")
			(pintype "passive")
		)
		(pad "2" smd roundrect
			(at 0.48 0 270)
			(size 0.59 0.64)
			(layers "B.Cu" "B.Mask" "B.Paste")
			(roundrect_rratio 0.25)
			(net 553 "/HDMI/HDMI_3V3")
			(pintype "passive")
		)
	)
	(footprint "antmicro-footprints:SOT-583"
		(layer "B.Cu")
		(at 219.35 129.899 -90)
		(property "Reference" "U5"
			(at -1.199 -1.95 180)
			(layer "B.SilkS")
			(effects
				(font
					(size 0.7 0.7)
					(thickness 0.15)
				)
				(justify left bottom mirror)
			)
		)
		(property "Value" "TPS2117DRLR"
			(at 0 -2.3 90)
			(layer "B.Fab")
			(hide yes)
			(effects
				(font
					(size 0.7 0.7)
					(thickness 0.15)
				)
				(justify left bottom mirror)
			)
		)
		(property "Datasheet" "https://www.ti.com/lit/ds/symlink/tps2117.pdf"
			(at 0 0 270)
			(layer "F.Fab")
			(hide yes)
			(effects
				(font
					(size 1.27 1.27)
					(thickness 0.15)
				)
			)
		)
		(property "Description" "TPS2117 1.6-V to 5.5-V, 4-A Low IQ Power Mux With Manual and Priority Switchover"
			(at 0 0 270)
			(layer "F.Fab")
			(hide yes)
			(effects
				(font
					(size 1.27 1.27)
					(thickness 0.15)
				)
			)
		)
		(property "Author" "Antmicro"
			(at 89.451 349.249 0)
			(layer "B.Fab")
			(hide yes)
			(effects
				(font
					(size 1 1)
					(thickness 0.15)
				)
				(justify mirror)
			)
		)
		(property "License" "Apache-2.0"
			(at 89.451 349.249 0)
			(layer "B.Fab")
			(hide yes)
			(effects
				(font
					(size 1 1)
					(thickness 0.15)
				)
				(justify mirror)
			)
		)
		(property "MPN" "TPS2117DRLR"
			(at 89.451 349.249 0)
			(layer "B.Fab")
			(hide yes)
			(effects
				(font
					(size 1 1)
					(thickness 0.15)
				)
				(justify mirror)
			)
		)
		(property "Manufacturer" "Texas Instruments"
			(at 89.451 349.249 0)
			(layer "B.Fab")
			(hide yes)
			(effects
				(font
					(size 1 1)
					(thickness 0.15)
				)
				(justify mirror)
			)
		)
		(property ki_fp_filters "DRL0008A-MFG")
		(sheetname "/Supply/")
		(sheetfile "supply.kicad_sch")
		(attr smd)
		(fp_line
			(start -0.65 1.15)
			(end 0.65 1.15)
			(stroke
				(width 0.15)
				(type solid)
			)
			(layer "B.SilkS")
		)
		(fp_line
			(start -0.651 -1.15)
			(end 0.651 -1.15)
			(stroke
				(width 0.15)
				(type solid)
			)
			(layer "B.SilkS")
		)
		(fp_circle
			(center -0.9 1.1)
			(end -0.85 1.05)
			(stroke
				(width 0.15)
				(type solid)
			)
			(fill yes)
			(layer "B.SilkS")
		)
		(fp_rect
			(start -1.15 1.3)
			(end 1.15 -1.3)
			(stroke
				(width 0.05)
				(type solid)
			)
			(fill no)
			(layer "B.CrtYd")
		)
		(fp_line
			(start -0.651 1.1005)
			(end 0.651 1.1005)
			(stroke
				(width 0.15)
				(type solid)
			)
			(layer "B.Fab")
		)
		(fp_line
			(start -0.651 -1.1005)
			(end -0.651 1.1005)
			(stroke
				(width 0.15)
				(type solid)
			)
			(layer "B.Fab")
		)
		(fp_line
			(start -0.651 -1.1005)
			(end 0.651 -1.1005)
			(stroke
				(width 0.15)
				(type solid)
			)
			(layer "B.Fab")
		)
		(fp_line
			(start 0.651 -1.1005)
			(end 0.651 1.1005)
			(stroke
				(width 0.15)
				(type solid)
			)
			(layer "B.Fab")
		)
		(fp_text user "${REFERENCE}"
			(at -0.06 -4.025 90)
			(layer "B.Fab")
			(effects
				(font
					(size 0.7 0.7)
					(thickness 0.15)
				)
				(justify left bottom mirror)
			)
		)
		(fp_text user "Author: Antmicro"
			(at -0.06 -5.025 90)
			(layer "B.Fab")
			(effects
				(font
					(size 0.7 0.7)
					(thickness 0.15)
				)
				(justify left bottom mirror)
			)
		)
		(fp_text user "License: Apache-2.0"
			(at -0.06 -6.025 90)
			(layer "B.Fab")
			(effects
				(font
					(size 0.7 0.7)
					(thickness 0.15)
				)
				(justify left bottom mirror)
			)
		)
		(pad "1" smd roundrect
			(at -0.739 0.7495 270)
			(size 0.670001 0.299999)
			(layers "B.Cu" "B.Mask" "B.Paste")
			(roundrect_rratio 0.25)
			(net 417 "GND")
			(pinfunction "GND")
			(pintype "power_in")
		)
		(pad "2" smd roundrect
			(at -0.739 0.2505 270)
			(size 0.670001 0.299999)
			(layers "B.Cu" "B.Mask" "B.Paste")
			(roundrect_rratio 0.25)
			(net 188 "Net-(R9-Pad1)")
			(pinfunction "VOUT")
			(pintype "power_out")
		)
		(pad "3" smd roundrect
			(at -0.739 -0.2495 270)
			(size 0.670001 0.299999)
			(layers "B.Cu" "B.Mask" "B.Paste")
			(roundrect_rratio 0.25)
			(net 50 "+3V3")
			(pinfunction "VIN1")
			(pintype "power_in")
		)
		(pad "4" smd roundrect
			(at -0.739 -0.7495 270)
			(size 0.670001 0.299999)
			(layers "B.Cu" "B.Mask" "B.Paste")
			(roundrect_rratio 0.25)
			(net 186 "/Supply/PR")
			(pinfunction "PR1")
			(pintype "input")
		)
		(pad "5" smd roundrect
			(at 0.74 -0.7495 270)
			(size 0.670001 0.299999)
			(layers "B.Cu" "B.Mask" "B.Paste")
			(roundrect_rratio 0.25)
			(net 50 "+3V3")
			(pinfunction "MODE")
			(pintype "input")
		)
		(pad "6" smd roundrect
			(at 0.74 -0.2495 270)
			(size 0.670001 0.299999)
			(layers "B.Cu" "B.Mask" "B.Paste")
			(roundrect_rratio 0.25)
			(net 418 "+2V5")
			(pinfunction "VIN2")
			(pintype "power_in")
		)
		(pad "7" smd roundrect
			(at 0.74 0.2505 270)
			(size 0.670001 0.299999)
			(layers "B.Cu" "B.Mask" "B.Paste")
			(roundrect_rratio 0.25)
			(net 188 "Net-(R9-Pad1)")
			(pinfunction "VOUT")
			(pintype "passive")
		)
		(pad "8" smd roundrect
			(at 0.74 0.7495 270)
			(size 0.670001 0.299999)
			(layers "B.Cu" "B.Mask" "B.Paste")
			(roundrect_rratio 0.25)
			(net 477 "unconnected-(U5-ST-Pad8)")
			(pinfunction "ST")
			(pintype "output+no_connect")
		)
	)
	(footprint "antmicro-footprints:C_0402_1005Metric"
		(layer "B.Cu")
		(at 196.09 136.67 90)
		(descr "Capacitor SMD 0402")
		(tags "capacitor SMD 0402")
		(property "Reference" "C46"
			(at 5.17 -9.615 90)
			(layer "B.SilkS")
			(effects
				(font
					(size 0.7 0.7)
					(thickness 0.15)
				)
				(justify right bottom mirror)
			)
		)
		(property "Value" "C_100n_0402"
			(at -1.022927 -2.155213 90)
			(layer "B.Fab")
			(hide yes)
			(effects
				(font
					(size 0.7 0.7)
					(thickness 0.15)
				)
				(justify right bottom mirror)
			)
		)
		(property "Datasheet" "https://www.murata.com/products/productdetail?partno=GRM155R61H104KE14%23"
			(at 0 0 90)
			(layer "F.Fab")
			(hide yes)
			(effects
				(font
					(size 1.27 1.27)
					(thickness 0.15)
				)
			)
		)
		(property "Description" "SMD Multilayer Ceramic Capacitor, 0.1 µF, 50 V, 0402 [1005 Metric], ± 10%, X5R, GRM Series"
			(at 0 0 90)
			(layer "F.Fab")
			(hide yes)
			(effects
				(font
					(size 1.27 1.27)
					(thickness 0.15)
				)
			)
		)
		(property "Author" "Antmicro"
			(at 332.76 -59.42 0)
			(layer "B.Fab")
			(hide yes)
			(effects
				(font
					(size 1 1)
					(thickness 0.15)
				)
				(justify mirror)
			)
		)
		(property "Dielectric" "X5R"
			(at 332.76 -59.42 0)
			(layer "B.Fab")
			(hide yes)
			(effects
				(font
					(size 1 1)
					(thickness 0.15)
				)
				(justify mirror)
			)
		)
		(property "License" "Apache-2.0"
			(at 332.76 -59.42 0)
			(layer "B.Fab")
			(hide yes)
			(effects
				(font
					(size 1 1)
					(thickness 0.15)
				)
				(justify mirror)
			)
		)
		(property "MPN" "GRM155R61H104KE14D"
			(at 332.76 -59.42 0)
			(layer "B.Fab")
			(hide yes)
			(effects
				(font
					(size 1 1)
					(thickness 0.15)
				)
				(justify mirror)
			)
		)
		(property "Manufacturer" "Murata"
			(at 332.76 -59.42 0)
			(layer "B.Fab")
			(hide yes)
			(effects
				(font
					(size 1 1)
					(thickness 0.15)
				)
				(justify mirror)
			)
		)
		(property "Public" ""
			(at 332.76 -59.42 0)
			(layer "B.Fab")
			(hide yes)
			(effects
				(font
					(size 1 1)
					(thickness 0.15)
				)
				(justify mirror)
			)
		)
		(property "Val" "100n"
			(at 332.76 -59.42 0)
			(layer "B.Fab")
			(hide yes)
			(effects
				(font
					(size 1 1)
					(thickness 0.15)
				)
				(justify mirror)
			)
		)
		(property "Voltage" "50V"
			(at 332.76 -59.42 0)
			(layer "B.Fab")
			(hide yes)
			(effects
				(font
					(size 1 1)
					(thickness 0.15)
				)
				(justify mirror)
			)
		)
		(sheetname "/FPGA Supply/")
		(sheetfile "fpga-supply.kicad_sch")
		(attr smd)
		(fp_rect
			(start -0.925 0.47)
			(end 0.925 -0.47)
			(stroke
				(width 0.05)
				(type default)
			)
			(fill no)
			(layer "B.CrtYd")
		)
		(fp_line
			(start 0.504 -0.248)
			(end -0.494 -0.248)
			(stroke
				(width 0.15)
				(type solid)
			)
			(layer "B.Fab")
		)
		(fp_line
			(start -0.494 -0.248)
			(end -0.494 0.25)
			(stroke
				(width 0.15)
				(type solid)
			)
			(layer "B.Fab")
		)
		(fp_line
			(start 0.504 0.25)
			(end 0.504 -0.248)
			(stroke
				(width 0.15)
				(type solid)
			)
			(layer "B.Fab")
		)
		(fp_line
			(start -0.494 0.25)
			(end 0.504 0.25)
			(stroke
				(width 0.15)
				(type solid)
			)
			(layer "B.Fab")
		)
		(fp_text user "${REFERENCE}"
			(at -0.939 -4.599 270)
			(layer "B.Fab")
			(effects
				(font
					(size 0.7 0.7)
					(thickness 0.15)
				)
				(justify left bottom mirror)
			)
		)
		(fp_text user "License: Apache-2.0"
			(at -0.939 -5.799 270)
			(layer "B.Fab")
			(effects
				(font
					(size 0.7 0.7)
					(thickness 0.15)
				)
				(justify left bottom mirror)
			)
		)
		(fp_text user "Author: Antmicro"
			(at -0.939 -3.399 270)
			(layer "B.Fab")
			(effects
				(font
					(size 0.7 0.7)
					(thickness 0.15)
				)
				(justify left bottom mirror)
			)
		)
		(pad "1" smd roundrect
			(at -0.48 0 90)
			(size 0.59 0.64)
			(layers "B.Cu" "B.Mask" "B.Paste")
			(roundrect_rratio 0.25)
			(net 417 "GND")
			(pintype "passive")
		)
		(pad "2" smd roundrect
			(at 0.48 0 90)
			(size 0.59 0.64)
			(layers "B.Cu" "B.Mask" "B.Paste")
			(roundrect_rratio 0.25)
			(net 48 "+1V8")
			(pintype "passive")
		)
	)
)
